(kicad_pcb
	(version 20260206)
	(generator "pcbnew")
	(generator_version "10.0")
	(general
		(thickness 1.6)
		(legacy_teardrops no)
	)
	(paper "A4")
	(title_block
		(title "dpb — 14545-sa.0730WZS0815.brd")
		(comment 1 "Honey Badger (Wiwynn) / footprints 808-814 of 1066")
	)
	(layers
		(0 "F.Cu" signal "TOP")
		(4 "In1.Cu" signal "L2GND")
		(6 "In2.Cu" signal "L3")
		(8 "In3.Cu" signal "L4VCC")
		(10 "In4.Cu" signal "L5VCC")
		(12 "In5.Cu" signal "L6")
		(14 "In6.Cu" signal "L7GND")
		(2 "B.Cu" signal "BOTTOM")
		(9 "F.Adhes" user "F.Adhesive")
		(11 "B.Adhes" user "B.Adhesive")
		(13 "F.Paste" user "Package Geometry/Pastemask Top")
		(15 "B.Paste" user "Package Geometry/Pastemask Bottom")
		(5 "F.SilkS" user "Ref Des/Silkscreen Top")
		(7 "B.SilkS" user "Ref Des/Silkscreen Bottom")
		(1 "F.Mask" user "Board Geometry/Soldermask Top")
		(3 "B.Mask" user "Board Geometry/Soldermask Bottom")
		(17 "Dwgs.User" user "User.Drawings")
		(19 "Cmts.User" user "User.Comments")
		(21 "Eco1.User" user "User.Eco1")
		(23 "Eco2.User" user "User.Eco2")
		(25 "Edge.Cuts" user "Board Geometry/Outline")
		(27 "Margin" user)
		(31 "F.CrtYd" user "Package Geometry/Place Bound Top")
		(29 "B.CrtYd" user "Package Geometry/Place Bound Bottom")
		(35 "F.Fab" user "Ref Des/Assembly Top")
		(33 "B.Fab" user "Ref Des/Assembly Bottom")
	)
	(footprint ""
		(layer "F.Cu")
		(at 32.86506 -366.075214 -90)
		(property "Reference" "C198"
			(at 0 0 270)
			(layer "F.SilkS")
			(hide yes)
			(effects
				(font
					(size 1.27 1.27)
				)
			)
		)
		(property "Value" "SCD01U50V2KX-1GP"
			(at 1.1811 -2.7051 270)
			(unlocked yes)
			(layer "F.Fab")
			(hide yes)
			(effects
				(font
					(size 1.016 1.016)
					(thickness 0.1524)
				)
			)
		)
		(property "Device Type" "C402H22"
			(at 1.1811 -4.2291 270)
			(unlocked yes)
			(layer "F.Fab")
			(hide yes)
			(effects
				(font
					(size 1.016 1.016)
					(thickness 0.1524)
				)
			)
		)
		(duplicate_pad_numbers_are_jumpers no)
		(fp_rect
			(start -0.4318 0.9525)
			(end 0.4318 -0.9525)
			(stroke
				(width 0)
				(type default)
			)
			(fill no)
			(layer "F.CrtYd")
		)
		(fp_rect
			(start -0.4318 0.9525)
			(end 0.4318 -0.9525)
			(stroke
				(width 0)
				(type default)
			)
			(fill no)
			(layer "F.Fab")
		)
		(pad "1" smd custom
			(at 0 -0.4445 270)
			(size 0.1524 0.1524)
			(layers "F.Cu" "F.Mask" "F.Paste")
			(net "SAS2X28_DRIVE_RX_N_A6")
			(options
				(clearance outline)
				(anchor circle)
			)
			(primitives
				(gr_poly
					(pts
						(arc
							(start 0.3048 -0.2032)
							(mid 0.275042 -0.275042)
							(end 0.2032 -0.3048)
						)
						(arc
							(start -0.2032 -0.3048)
							(mid -0.275042 -0.275042)
							(end -0.3048 -0.2032)
						)
						(arc
							(start -0.3048 0.2032)
							(mid -0.275042 0.275042)
							(end -0.2032 0.3048)
						)
						(arc
							(start 0.2032 0.3048)
							(mid 0.275042 0.275042)
							(end 0.3048 0.2032)
						)
					)
					(width 0)
					(fill yes)
				)
			)
		)
		(pad "2" smd custom
			(at 0 0.4445 270)
			(size 0.1524 0.1524)
			(layers "F.Cu" "F.Mask" "F.Paste")
			(net "SAS2X28_A_HDD6_RX_-")
			(options
				(clearance outline)
				(anchor circle)
			)
			(primitives
				(gr_poly
					(pts
						(arc
							(start 0.3048 -0.2032)
							(mid 0.275042 -0.275042)
							(end 0.2032 -0.3048)
						)
						(arc
							(start -0.2032 -0.3048)
							(mid -0.275042 -0.275042)
							(end -0.3048 -0.2032)
						)
						(arc
							(start -0.3048 0.2032)
							(mid -0.275042 0.275042)
							(end -0.2032 0.3048)
						)
						(arc
							(start 0.2032 0.3048)
							(mid 0.275042 0.275042)
							(end 0.3048 0.2032)
						)
					)
					(width 0)
					(fill yes)
				)
			)
		)
	)
	(footprint ""
		(layer "F.Cu")
		(at 234.695746 -43.8277 90)
		(property "Reference" "R156"
			(at 0 0 90)
			(layer "F.SilkS")
			(hide yes)
			(effects
				(font
					(size 1.27 1.27)
				)
			)
		)
		(property "Value" "10KR2F-2-GP"
			(at 0.064008 -3.993896 90)
			(unlocked yes)
			(layer "F.Fab")
			(hide yes)
			(effects
				(font
					(size 1.016 1.016)
					(thickness 0.1524)
				)
			)
		)
		(property "Device Type" "R402H16"
			(at 0.064008 -5.517896 90)
			(unlocked yes)
			(layer "F.Fab")
			(hide yes)
			(effects
				(font
					(size 1.016 1.016)
					(thickness 0.1524)
				)
			)
		)
		(duplicate_pad_numbers_are_jumpers no)
		(fp_line
			(start 0.508 -0.9398)
			(end -0.508 -0.9398)
			(stroke
				(width 0.1524)
				(type default)
			)
			(layer "F.SilkS")
		)
		(fp_line
			(start -0.508 -0.9398)
			(end -0.508 0.9398)
			(stroke
				(width 0.1524)
				(type default)
			)
			(layer "F.SilkS")
		)
		(fp_rect
			(start -0.508 0.9398)
			(end 0.508 -0.9398)
			(stroke
				(width 0)
				(type default)
			)
			(fill no)
			(layer "F.CrtYd")
		)
		(fp_rect
			(start -0.508 0.9398)
			(end 0.508 -0.9398)
			(stroke
				(width 0)
				(type default)
			)
			(fill no)
			(layer "F.Fab")
		)
		(pad "1" smd custom
			(at 0 -0.4445 90)
			(size 0.1397 0.1397)
			(layers "F.Cu" "F.Mask" "F.Paste")
			(net "P5VA")
			(options
				(clearance outline)
				(anchor circle)
			)
			(primitives
				(gr_poly
					(pts
						(arc
							(start -0.1778 -0.2794)
							(mid -0.249642 -0.249642)
							(end -0.2794 -0.1778)
						)
						(arc
							(start -0.2794 0.1778)
							(mid -0.249642 0.249642)
							(end -0.1778 0.2794)
						)
						(arc
							(start 0.1778 0.2794)
							(mid 0.249642 0.249642)
							(end 0.2794 0.1778)
						)
						(arc
							(start 0.2794 -0.1778)
							(mid 0.249642 -0.249642)
							(end 0.1778 -0.2794)
						)
					)
					(width 0)
					(fill yes)
				)
			)
		)
		(pad "2" smd custom
			(at 0 0.4445 90)
			(size 0.1397 0.1397)
			(layers "F.Cu" "F.Mask" "F.Paste")
			(net "DRIVE_ACT_4")
			(options
				(clearance outline)
				(anchor circle)
			)
			(primitives
				(gr_poly
					(pts
						(arc
							(start -0.1778 -0.2794)
							(mid -0.249642 -0.249642)
							(end -0.2794 -0.1778)
						)
						(arc
							(start -0.2794 0.1778)
							(mid -0.249642 0.249642)
							(end -0.1778 0.2794)
						)
						(arc
							(start 0.1778 0.2794)
							(mid 0.249642 0.249642)
							(end 0.2794 0.1778)
						)
						(arc
							(start 0.2794 -0.1778)
							(mid 0.249642 -0.249642)
							(end 0.1778 -0.2794)
						)
					)
					(width 0)
					(fill yes)
				)
			)
		)
	)
	(footprint ""
		(layer "F.Cu")
		(at 242.061746 -24.3967 90)
		(property "Reference" "PC10"
			(at 0 0 90)
			(layer "F.SilkS")
			(hide yes)
			(effects
				(font
					(size 1.27 1.27)
				)
			)
		)
		(property "Value" "SC1U10V2KX-1GP"
			(at 1.1811 -2.7051 90)
			(unlocked yes)
			(layer "F.Fab")
			(hide yes)
			(effects
				(font
					(size 1.016 1.016)
					(thickness 0.1524)
				)
			)
		)
		(property "Device Type" "C402H22"
			(at 1.1811 -4.2291 90)
			(unlocked yes)
			(layer "F.Fab")
			(hide yes)
			(effects
				(font
					(size 1.016 1.016)
					(thickness 0.1524)
				)
			)
		)
		(duplicate_pad_numbers_are_jumpers no)
		(fp_rect
			(start -0.4318 0.9525)
			(end 0.4318 -0.9525)
			(stroke
				(width 0)
				(type default)
			)
			(fill no)
			(layer "F.CrtYd")
		)
		(fp_rect
			(start -0.4318 0.9525)
			(end 0.4318 -0.9525)
			(stroke
				(width 0)
				(type default)
			)
			(fill no)
			(layer "F.Fab")
		)
		(pad "1" smd custom
			(at 0 -0.4445 90)
			(size 0.1524 0.1524)
			(layers "F.Cu" "F.Mask" "F.Paste")
			(net "P5VA_VREG")
			(options
				(clearance outline)
				(anchor circle)
			)
			(primitives
				(gr_poly
					(pts
						(arc
							(start 0.3048 -0.2032)
							(mid 0.275042 -0.275042)
							(end 0.2032 -0.3048)
						)
						(arc
							(start -0.2032 -0.3048)
							(mid -0.275042 -0.275042)
							(end -0.3048 -0.2032)
						)
						(arc
							(start -0.3048 0.2032)
							(mid -0.275042 0.275042)
							(end -0.2032 0.3048)
						)
						(arc
							(start 0.2032 0.3048)
							(mid 0.275042 0.275042)
							(end 0.3048 0.2032)
						)
					)
					(width 0)
					(fill yes)
				)
			)
		)
		(pad "2" smd custom
			(at 0 0.4445 90)
			(size 0.1524 0.1524)
			(layers "F.Cu" "F.Mask" "F.Paste")
			(net "GND")
			(options
				(clearance outline)
				(anchor circle)
			)
			(primitives
				(gr_poly
					(pts
						(arc
							(start 0.3048 -0.2032)
							(mid 0.275042 -0.275042)
							(end 0.2032 -0.3048)
						)
						(arc
							(start -0.2032 -0.3048)
							(mid -0.275042 -0.275042)
							(end -0.3048 -0.2032)
						)
						(arc
							(start -0.3048 0.2032)
							(mid -0.275042 0.275042)
							(end -0.2032 0.3048)
						)
						(arc
							(start 0.2032 0.3048)
							(mid 0.275042 0.275042)
							(end 0.3048 0.2032)
						)
					)
					(width 0)
					(fill yes)
				)
			)
		)
	)
	(footprint ""
		(layer "F.Cu")
		(at 42.6466 -116.4844)
		(property "Reference" "C321"
			(at 0 0 0)
			(layer "F.SilkS")
			(hide yes)
			(effects
				(font
					(size 1.27 1.27)
				)
			)
		)
		(property "Value" "SC10U25V6KX-1GP"
			(at -0.0762 -5.1308 0)
			(unlocked yes)
			(layer "F.Fab")
			(hide yes)
			(effects
				(font
					(size 1.016 1.016)
					(thickness 0.1524)
				)
			)
		)
		(property "Device Type" "C1206H71"
			(at -0.127 -6.6548 0)
			(unlocked yes)
			(layer "F.Fab")
			(hide yes)
			(effects
				(font
					(size 1.016 1.016)
					(thickness 0.1524)
				)
			)
		)
		(duplicate_pad_numbers_are_jumpers no)
		(fp_line
			(start -1.016 -2.2352)
			(end 1.016 -2.2352)
			(stroke
				(width 0.1524)
				(type default)
			)
			(layer "F.SilkS")
		)
		(fp_line
			(start -1.016 -0.8382)
			(end -1.016 -2.2352)
			(stroke
				(width 0.1524)
				(type default)
			)
			(layer "F.SilkS")
		)
		(fp_line
			(start -1.016 2.2352)
			(end -1.016 0.8382)
			(stroke
				(width 0.1524)
				(type default)
			)
			(layer "F.SilkS")
		)
		(fp_line
			(start 1.016 -2.2352)
			(end 1.016 -0.8382)
			(stroke
				(width 0.1524)
				(type default)
			)
			(layer "F.SilkS")
		)
		(fp_line
			(start 1.016 0.8382)
			(end 1.016 2.2352)
			(stroke
				(width 0.1524)
				(type default)
			)
			(layer "F.SilkS")
		)
		(fp_line
			(start 1.016 2.2352)
			(end -1.016 2.2352)
			(stroke
				(width 0.1524)
				(type default)
			)
			(layer "F.SilkS")
		)
		(fp_rect
			(start -1.0922 2.3114)
			(end 1.0922 -2.3114)
			(stroke
				(width 0)
				(type default)
			)
			(fill no)
			(layer "F.CrtYd")
		)
		(fp_poly
			(pts
				(xy 1.0922 -2.3114) (xy 1.0922 2.3114) (xy -1.0922 2.3114) (xy -1.0922 -2.3114)
			)
			(stroke
				(width 0)
				(type default)
			)
			(fill no)
			(layer "F.Fab")
		)
		(pad "1" smd rect
			(at 0 -1.397)
			(size 1.651 1.27)
			(layers "F.Cu" "F.Mask" "F.Paste")
			(net "P12V_HDD13")
		)
		(pad "2" smd rect
			(at 0 1.397)
			(size 1.651 1.27)
			(layers "F.Cu" "F.Mask" "F.Paste")
			(net "GND")
		)
	)
	(footprint ""
		(layer "F.Cu")
		(at 26.796746 -448.0687 90)
		(property "Reference" "C263"
			(at 0 0 90)
			(layer "F.SilkS")
			(hide yes)
			(effects
				(font
					(size 1.27 1.27)
				)
			)
		)
		(property "Value" "SCD01U50V2KX-1GP"
			(at 1.1811 -2.7051 90)
			(unlocked yes)
			(layer "F.Fab")
			(hide yes)
			(effects
				(font
					(size 1.016 1.016)
					(thickness 0.1524)
				)
			)
		)
		(property "Device Type" "C402H22"
			(at 1.1811 -4.2291 90)
			(unlocked yes)
			(layer "F.Fab")
			(hide yes)
			(effects
				(font
					(size 1.016 1.016)
					(thickness 0.1524)
				)
			)
		)
		(duplicate_pad_numbers_are_jumpers no)
		(fp_rect
			(start -0.4318 0.9525)
			(end 0.4318 -0.9525)
			(stroke
				(width 0)
				(type default)
			)
			(fill no)
			(layer "F.CrtYd")
		)
		(fp_rect
			(start -0.4318 0.9525)
			(end 0.4318 -0.9525)
			(stroke
				(width 0)
				(type default)
			)
			(fill no)
			(layer "F.Fab")
		)
		(pad "1" smd custom
			(at 0 -0.4445 90)
			(size 0.1524 0.1524)
			(layers "F.Cu" "F.Mask" "F.Paste")
			(net "SAS2X28_DRIVE_RX_P_A10")
			(options
				(clearance outline)
				(anchor circle)
			)
			(primitives
				(gr_poly
					(pts
						(arc
							(start 0.3048 -0.2032)
							(mid 0.275042 -0.275042)
							(end 0.2032 -0.3048)
						)
						(arc
							(start -0.2032 -0.3048)
							(mid -0.275042 -0.275042)
							(end -0.3048 -0.2032)
						)
						(arc
							(start -0.3048 0.2032)
							(mid -0.275042 0.275042)
							(end -0.2032 0.3048)
						)
						(arc
							(start 0.2032 0.3048)
							(mid 0.275042 0.275042)
							(end 0.3048 0.2032)
						)
					)
					(width 0)
					(fill yes)
				)
			)
		)
		(pad "2" smd custom
			(at 0 0.4445 90)
			(size 0.1524 0.1524)
			(layers "F.Cu" "F.Mask" "F.Paste")
			(net "SAS2X28_A_HDD10_RX_+")
			(options
				(clearance outline)
				(anchor circle)
			)
			(primitives
				(gr_poly
					(pts
						(arc
							(start 0.3048 -0.2032)
							(mid 0.275042 -0.275042)
							(end 0.2032 -0.3048)
						)
						(arc
							(start -0.2032 -0.3048)
							(mid -0.275042 -0.275042)
							(end -0.3048 -0.2032)
						)
						(arc
							(start -0.3048 0.2032)
							(mid -0.275042 0.275042)
							(end -0.2032 0.3048)
						)
						(arc
							(start 0.2032 0.3048)
							(mid 0.275042 0.275042)
							(end 0.3048 0.2032)
						)
					)
					(width 0)
					(fill yes)
				)
			)
		)
	)
	(footprint ""
		(layer "F.Cu")
		(at 41.401746 -113.185702)
		(property "Reference" "R288"
			(at 0 0 0)
			(layer "F.SilkS")
			(hide yes)
			(effects
				(font
					(size 1.27 1.27)
				)
			)
		)
		(property "Value" "200KR2F-L-GP"
			(at 0.064008 -3.993896 0)
			(unlocked yes)
			(layer "F.Fab")
			(hide yes)
			(effects
				(font
					(size 1.016 1.016)
					(thickness 0.1524)
				)
			)
		)
		(property "Device Type" "R402H16"
			(at 0.064008 -5.517896 0)
			(unlocked yes)
			(layer "F.Fab")
			(hide yes)
			(effects
				(font
					(size 1.016 1.016)
					(thickness 0.1524)
				)
			)
		)
		(duplicate_pad_numbers_are_jumpers no)
		(fp_line
			(start -0.508 -0.9398)
			(end -0.508 0.9398)
			(stroke
				(width 0.1524)
				(type default)
			)
			(layer "F.SilkS")
		)
		(fp_line
			(start 0.508 -0.9398)
			(end -0.508 -0.9398)
			(stroke
				(width 0.1524)
				(type default)
			)
			(layer "F.SilkS")
		)
		(fp_rect
			(start -0.508 0.9398)
			(end 0.508 -0.9398)
			(stroke
				(width 0)
				(type default)
			)
			(fill no)
			(layer "F.CrtYd")
		)
		(fp_rect
			(start -0.508 0.9398)
			(end 0.508 -0.9398)
			(stroke
				(width 0)
				(type default)
			)
			(fill no)
			(layer "F.Fab")
		)
		(pad "1" smd custom
			(at 0 -0.4445)
			(size 0.1397 0.1397)
			(layers "F.Cu" "F.Mask" "F.Paste")
			(net "P12V")
			(options
				(clearance outline)
				(anchor circle)
			)
			(primitives
				(gr_poly
					(pts
						(arc
							(start -0.1778 -0.2794)
							(mid -0.249642 -0.249642)
							(end -0.2794 -0.1778)
						)
						(arc
							(start -0.2794 0.1778)
							(mid -0.249642 0.249642)
							(end -0.1778 0.2794)
						)
						(arc
							(start 0.1778 0.2794)
							(mid 0.249642 0.249642)
							(end 0.2794 0.1778)
						)
						(arc
							(start 0.2794 -0.1778)
							(mid 0.249642 -0.249642)
							(end 0.1778 -0.2794)
						)
					)
					(width 0)
					(fill yes)
				)
			)
		)
		(pad "2" smd custom
			(at 0 0.4445)
			(size 0.1397 0.1397)
			(layers "F.Cu" "F.Mask" "F.Paste")
			(net "SW_HDD13_P")
			(options
				(clearance outline)
				(anchor circle)
			)
			(primitives
				(gr_poly
					(pts
						(arc
							(start -0.1778 -0.2794)
							(mid -0.249642 -0.249642)
							(end -0.2794 -0.1778)
						)
						(arc
							(start -0.2794 0.1778)
							(mid -0.249642 0.249642)
							(end -0.1778 0.2794)
						)
						(arc
							(start 0.1778 0.2794)
							(mid 0.249642 0.249642)
							(end 0.2794 0.1778)
						)
						(arc
							(start 0.2794 -0.1778)
							(mid 0.249642 -0.249642)
							(end 0.1778 -0.2794)
						)
					)
					(width 0)
					(fill yes)
				)
			)
		)
	)
	(footprint ""
		(layer "F.Cu")
		(at 197.230746 -492.5187 -90)
		(property "Reference" "R425"
			(at 0 0 270)
			(layer "F.SilkS")
			(hide yes)
			(effects
				(font
					(size 1.27 1.27)
				)
			)
		)
		(property "Value" "4K7R2J-2-GP"
			(at 0.064008 -3.993896 270)
			(unlocked yes)
			(layer "F.Fab")
			(hide yes)
			(effects
				(font
					(size 1.016 1.016)
					(thickness 0.1524)
				)
			)
		)
		(property "Device Type" "R402H16"
			(at 0.064008 -5.517896 270)
			(unlocked yes)
			(layer "F.Fab")
			(hide yes)
			(effects
				(font
					(size 1.016 1.016)
					(thickness 0.1524)
				)
			)
		)
		(duplicate_pad_numbers_are_jumpers no)
		(fp_line
			(start -0.508 -0.9398)
			(end -0.508 0.9398)
			(stroke
				(width 0.1524)
				(type default)
			)
			(layer "F.SilkS")
		)
		(fp_line
			(start 0.508 -0.9398)
			(end -0.508 -0.9398)
			(stroke
				(width 0.1524)
				(type default)
			)
			(layer "F.SilkS")
		)
		(fp_rect
			(start -0.508 0.9398)
			(end 0.508 -0.9398)
			(stroke
				(width 0)
				(type default)
			)
			(fill no)
			(layer "F.CrtYd")
		)
		(fp_rect
			(start -0.508 0.9398)
			(end 0.508 -0.9398)
			(stroke
				(width 0)
				(type default)
			)
			(fill no)
			(layer "F.Fab")
		)
		(pad "1" smd custom
			(at 0 -0.4445 270)
			(size 0.1397 0.1397)
			(layers "F.Cu" "F.Mask" "F.Paste")
			(net "P3V3")
			(options
				(clearance outline)
				(anchor circle)
			)
			(primitives
				(gr_poly
					(pts
						(arc
							(start -0.1778 -0.2794)
							(mid -0.249642 -0.249642)
							(end -0.2794 -0.1778)
						)
						(arc
							(start -0.2794 0.1778)
							(mid -0.249642 0.249642)
							(end -0.1778 0.2794)
						)
						(arc
							(start 0.1778 0.2794)
							(mid 0.249642 0.249642)
							(end 0.2794 0.1778)
						)
						(arc
							(start 0.2794 -0.1778)
							(mid 0.249642 -0.249642)
							(end 0.1778 -0.2794)
						)
					)
					(width 0)
					(fill yes)
				)
			)
		)
		(pad "2" smd custom
			(at 0 0.4445 270)
			(size 0.1397 0.1397)
			(layers "F.Cu" "F.Mask" "F.Paste")
			(net "SAS_EXP_A_PWR0")
			(options
				(clearance outline)
				(anchor circle)
			)
			(primitives
				(gr_poly
					(pts
						(arc
							(start -0.1778 -0.2794)
							(mid -0.249642 -0.249642)
							(end -0.2794 -0.1778)
						)
						(arc
							(start -0.2794 0.1778)
							(mid -0.249642 0.249642)
							(end -0.1778 0.2794)
						)
						(arc
							(start 0.1778 0.2794)
							(mid 0.249642 0.249642)
							(end 0.2794 0.1778)
						)
						(arc
							(start 0.2794 -0.1778)
							(mid 0.249642 -0.249642)
							(end 0.1778 -0.2794)
						)
					)
					(width 0)
					(fill yes)
				)
			)
		)
	)
)
